(kicad_pcb
	(version 20260206)
	(generator "pcbnew")
	(generator_version "10.0")
	(general
		(thickness 1.6)
		(legacy_teardrops no)
	)
	(paper "A4")
	(title_block
		(title "04192023_DAF0TMB3IC0_F0TG_MB_C_brd_V02_OCP.brd")
		(comment 1 "Grand Teton / footprints 1869-1871 of 8354")
	)
	(layers
		(0 "F.Cu" signal "TOP")
		(4 "In1.Cu" signal "GND")
		(6 "In2.Cu" signal "IN1")
		(8 "In3.Cu" signal "GND1")
		(10 "In4.Cu" signal "IN2")
		(12 "In5.Cu" signal "GND2")
		(14 "In6.Cu" signal "IN3")
		(16 "In7.Cu" signal "GND3")
		(18 "In8.Cu" signal "VCC")
		(20 "In9.Cu" signal "VCC1")
		(22 "In10.Cu" signal "GND4")
		(24 "In11.Cu" signal "IN4")
		(26 "In12.Cu" signal "GND5")
		(28 "In13.Cu" signal "IN5")
		(30 "In14.Cu" signal "GND6")
		(32 "In15.Cu" signal "IN6")
		(34 "In16.Cu" signal "GND7")
		(2 "B.Cu" signal "BOTTOM")
		(9 "F.Adhes" user "F.Adhesive")
		(11 "B.Adhes" user "B.Adhesive")
		(13 "F.Paste" user "Package Geometry/Pastemask Top")
		(15 "B.Paste" user "Package Geometry/Pastemask Bottom")
		(5 "F.SilkS" user "Ref Des/Silkscreen Top")
		(7 "B.SilkS" user "Ref Des/Silkscreen Bottom")
		(1 "F.Mask" user "Board Geometry/Soldermask Top")
		(3 "B.Mask" user "Board Geometry/Soldermask Bottom")
		(17 "Dwgs.User" user "User.Drawings")
		(19 "Cmts.User" user "User.Comments")
		(21 "Eco1.User" user "User.Eco1")
		(23 "Eco2.User" user "User.Eco2")
		(25 "Edge.Cuts" user "Board Geometry/Outline")
		(27 "Margin" user)
		(31 "F.CrtYd" user "Package Geometry/Place Bound Top")
		(29 "B.CrtYd" user "Package Geometry/Place Bound Bottom")
		(35 "F.Fab" user "Ref Des/Assembly Top")
		(33 "B.Fab" user "Ref Des/Assembly Bottom")
	)
	(footprint ""
		(layer "F.Cu")
		(at 358.465882 -256.012188 90)
		(property "Reference" "C3928"
			(at 0 0 90)
			(layer "F.SilkS")
			(hide yes)
			(effects
				(font
					(size 1.27 1.27)
				)
			)
		)
		(property "Value" ""
			(at 0 0 90)
			(layer "F.Fab")
			(effects
				(font
					(size 1.27 1.27)
				)
			)
		)
		(duplicate_pad_numbers_are_jumpers no)
		(fp_line
			(start 0.7874 -0.4064)
			(end 0.7874 0.4064)
			(stroke
				(width 0.1524)
				(type default)
			)
			(layer "F.SilkS")
		)
		(fp_line
			(start -0.7874 -0.4064)
			(end 0.7874 -0.4064)
			(stroke
				(width 0.1524)
				(type default)
			)
			(layer "F.SilkS")
		)
		(fp_line
			(start 0.7874 0.4064)
			(end -0.7874 0.4064)
			(stroke
				(width 0.1524)
				(type default)
			)
			(layer "F.SilkS")
		)
		(fp_line
			(start -0.7874 0.4064)
			(end -0.7874 -0.4064)
			(stroke
				(width 0.1524)
				(type default)
			)
			(layer "F.SilkS")
		)
		(fp_line
			(start -0.12065 -0.305054)
			(end -0.12065 -0.2794)
			(stroke
				(width 0.1)
				(type default)
			)
			(layer "F.Fab")
		)
		(fp_line
			(start -0.67945 -0.305054)
			(end -0.12065 -0.305054)
			(stroke
				(width 0.1)
				(type default)
			)
			(layer "F.Fab")
		)
		(fp_line
			(start 0.67945 -0.3048)
			(end 0.67945 0.3048)
			(stroke
				(width 0.1)
				(type default)
			)
			(layer "F.Fab")
		)
		(fp_line
			(start 0.12065 -0.3048)
			(end 0.67945 -0.3048)
			(stroke
				(width 0.1)
				(type default)
			)
			(layer "F.Fab")
		)
		(fp_line
			(start 0.12065 -0.2794)
			(end 0.12065 -0.3048)
			(stroke
				(width 0.1)
				(type default)
			)
			(layer "F.Fab")
		)
		(fp_line
			(start -0.12065 -0.2794)
			(end 0.12065 -0.2794)
			(stroke
				(width 0.1)
				(type default)
			)
			(layer "F.Fab")
		)
		(fp_line
			(start 0.120396 0.2794)
			(end -0.12065 0.2794)
			(stroke
				(width 0.1)
				(type default)
			)
			(layer "F.Fab")
		)
		(fp_line
			(start -0.12065 0.2794)
			(end -0.12065 0.3048)
			(stroke
				(width 0.1)
				(type default)
			)
			(layer "F.Fab")
		)
		(fp_line
			(start 0.67945 0.3048)
			(end 0.120396 0.3048)
			(stroke
				(width 0.1)
				(type default)
			)
			(layer "F.Fab")
		)
		(fp_line
			(start 0.120396 0.3048)
			(end 0.120396 0.2794)
			(stroke
				(width 0.1)
				(type default)
			)
			(layer "F.Fab")
		)
		(fp_line
			(start -0.12065 0.3048)
			(end -0.67945 0.3048)
			(stroke
				(width 0.1)
				(type default)
			)
			(layer "F.Fab")
		)
		(fp_line
			(start -0.67945 0.3048)
			(end -0.67945 -0.305054)
			(stroke
				(width 0.1)
				(type default)
			)
			(layer "F.Fab")
		)
		(pad "1" smd circle
			(at -0.40005 0 90)
			(size 0 0)
			(layers "F.Cu" "F.Mask" "F.Paste")
			(net "PVDDCR_SOC_P0")
		)
		(pad "2" smd circle
			(at 0.40005 0 90)
			(size 0 0)
			(layers "F.Cu" "F.Mask" "F.Paste")
			(net "GND")
		)
	)
	(footprint ""
		(layer "F.Cu")
		(at 452.756016 -46.345602 180)
		(property "Reference" "PR836"
			(at 0 0 180)
			(layer "F.SilkS")
			(hide yes)
			(effects
				(font
					(size 1.27 1.27)
				)
			)
		)
		(property "Value" ""
			(at 0 0 180)
			(layer "F.Fab")
			(effects
				(font
					(size 1.27 1.27)
				)
			)
		)
		(duplicate_pad_numbers_are_jumpers no)
		(fp_line
			(start 0.7874 0.4064)
			(end -0.7874 0.4064)
			(stroke
				(width 0.1524)
				(type default)
			)
			(layer "F.SilkS")
		)
		(fp_line
			(start 0.7874 -0.4064)
			(end 0.7874 0.4064)
			(stroke
				(width 0.1524)
				(type default)
			)
			(layer "F.SilkS")
		)
		(fp_line
			(start -0.7874 0.4064)
			(end -0.7874 -0.4064)
			(stroke
				(width 0.1524)
				(type default)
			)
			(layer "F.SilkS")
		)
		(fp_line
			(start -0.7874 -0.4064)
			(end 0.7874 -0.4064)
			(stroke
				(width 0.1524)
				(type default)
			)
			(layer "F.SilkS")
		)
		(fp_line
			(start 0.67945 0.3048)
			(end 0.120396 0.3048)
			(stroke
				(width 0.1)
				(type default)
			)
			(layer "F.Fab")
		)
		(fp_line
			(start 0.67945 -0.3048)
			(end 0.67945 0.3048)
			(stroke
				(width 0.1)
				(type default)
			)
			(layer "F.Fab")
		)
		(fp_line
			(start 0.12065 -0.2794)
			(end 0.12065 -0.3048)
			(stroke
				(width 0.1)
				(type default)
			)
			(layer "F.Fab")
		)
		(fp_line
			(start 0.12065 -0.3048)
			(end 0.67945 -0.3048)
			(stroke
				(width 0.1)
				(type default)
			)
			(layer "F.Fab")
		)
		(fp_line
			(start 0.120396 0.3048)
			(end 0.120396 0.2794)
			(stroke
				(width 0.1)
				(type default)
			)
			(layer "F.Fab")
		)
		(fp_line
			(start 0.120396 0.2794)
			(end -0.12065 0.2794)
			(stroke
				(width 0.1)
				(type default)
			)
			(layer "F.Fab")
		)
		(fp_line
			(start -0.12065 0.3048)
			(end -0.67945 0.3048)
			(stroke
				(width 0.1)
				(type default)
			)
			(layer "F.Fab")
		)
		(fp_line
			(start -0.12065 0.2794)
			(end -0.12065 0.3048)
			(stroke
				(width 0.1)
				(type default)
			)
			(layer "F.Fab")
		)
		(fp_line
			(start -0.12065 -0.2794)
			(end 0.12065 -0.2794)
			(stroke
				(width 0.1)
				(type default)
			)
			(layer "F.Fab")
		)
		(fp_line
			(start -0.12065 -0.305054)
			(end -0.12065 -0.2794)
			(stroke
				(width 0.1)
				(type default)
			)
			(layer "F.Fab")
		)
		(fp_line
			(start -0.67945 0.3048)
			(end -0.67945 -0.305054)
			(stroke
				(width 0.1)
				(type default)
			)
			(layer "F.Fab")
		)
		(fp_line
			(start -0.67945 -0.305054)
			(end -0.12065 -0.305054)
			(stroke
				(width 0.1)
				(type default)
			)
			(layer "F.Fab")
		)
		(pad "1" smd circle
			(at -0.40005 0 180)
			(size 0 0)
			(layers "F.Cu" "F.Mask" "F.Paste")
			(net "P3V3_AUX_VOS")
		)
		(pad "2" smd circle
			(at 0.40005 0 180)
			(size 0 0)
			(layers "F.Cu" "F.Mask" "F.Paste")
			(net "P3V3_AUX")
		)
	)
	(footprint ""
		(layer "F.Cu")
		(at 302.523398 -430.2379 180)
		(property "Reference" "C16"
			(at 0 0 180)
			(layer "F.SilkS")
			(hide yes)
			(effects
				(font
					(size 1.27 1.27)
				)
			)
		)
		(property "Value" ""
			(at 0 0 180)
			(layer "F.Fab")
			(effects
				(font
					(size 1.27 1.27)
				)
			)
		)
		(duplicate_pad_numbers_are_jumpers no)
		(fp_line
			(start 0.7874 0.4064)
			(end -0.7874 0.4064)
			(stroke
				(width 0.1524)
				(type default)
			)
			(layer "F.SilkS")
		)
		(fp_line
			(start 0.7874 -0.4064)
			(end 0.7874 0.4064)
			(stroke
				(width 0.1524)
				(type default)
			)
			(layer "F.SilkS")
		)
		(fp_line
			(start -0.7874 0.4064)
			(end -0.7874 -0.4064)
			(stroke
				(width 0.1524)
				(type default)
			)
			(layer "F.SilkS")
		)
		(fp_line
			(start -0.7874 -0.4064)
			(end 0.7874 -0.4064)
			(stroke
				(width 0.1524)
				(type default)
			)
			(layer "F.SilkS")
		)
		(fp_line
			(start 0.67945 0.3048)
			(end 0.120396 0.3048)
			(stroke
				(width 0.1)
				(type default)
			)
			(layer "F.Fab")
		)
		(fp_line
			(start 0.67945 -0.3048)
			(end 0.67945 0.3048)
			(stroke
				(width 0.1)
				(type default)
			)
			(layer "F.Fab")
		)
		(fp_line
			(start 0.12065 -0.2794)
			(end 0.12065 -0.3048)
			(stroke
				(width 0.1)
				(type default)
			)
			(layer "F.Fab")
		)
		(fp_line
			(start 0.12065 -0.3048)
			(end 0.67945 -0.3048)
			(stroke
				(width 0.1)
				(type default)
			)
			(layer "F.Fab")
		)
		(fp_line
			(start 0.120396 0.3048)
			(end 0.120396 0.2794)
			(stroke
				(width 0.1)
				(type default)
			)
			(layer "F.Fab")
		)
		(fp_line
			(start 0.120396 0.2794)
			(end -0.12065 0.2794)
			(stroke
				(width 0.1)
				(type default)
			)
			(layer "F.Fab")
		)
		(fp_line
			(start -0.12065 0.3048)
			(end -0.67945 0.3048)
			(stroke
				(width 0.1)
				(type default)
			)
			(layer "F.Fab")
		)
		(fp_line
			(start -0.12065 0.2794)
			(end -0.12065 0.3048)
			(stroke
				(width 0.1)
				(type default)
			)
			(layer "F.Fab")
		)
		(fp_line
			(start -0.12065 -0.2794)
			(end 0.12065 -0.2794)
			(stroke
				(width 0.1)
				(type default)
			)
			(layer "F.Fab")
		)
		(fp_line
			(start -0.12065 -0.305054)
			(end -0.12065 -0.2794)
			(stroke
				(width 0.1)
				(type default)
			)
			(layer "F.Fab")
		)
		(fp_line
			(start -0.67945 0.3048)
			(end -0.67945 -0.305054)
			(stroke
				(width 0.1)
				(type default)
			)
			(layer "F.Fab")
		)
		(fp_line
			(start -0.67945 -0.305054)
			(end -0.12065 -0.305054)
			(stroke
				(width 0.1)
				(type default)
			)
			(layer "F.Fab")
		)
		(pad "1" smd circle
			(at -0.40005 0 180)
			(size 0 0)
			(layers "F.Cu" "F.Mask" "F.Paste")
			(net "GPU_3V3IO_RSVD3_FFU_ISO")
		)
		(pad "2" smd circle
			(at 0.40005 0 180)
			(size 0 0)
			(layers "F.Cu" "F.Mask" "F.Paste")
			(net "GND")
		)
	)
)
